# TIMECARD (Time Appliance Project (Time Card)) — schematic netlist excerpt (pin names and nets, part order shuffled) for the footprints in the layout excerpt that follows; sources: Cadence DE-HDL packaged netlist, KiCad conversion of R4006-B0001-02_R01.brd

R39  RESISTOR  2.2OHM 1%  pkg SMC_0805R_H026  page 28 : \1\ = UNNAMED_517_CAPACITOR_I29_2 ; \2\ = SG
R363  RESISTOR  33OHM 1%  pkg SMC_0402R_H016  page 20 : \1\ = R_BNO080_EVN_SCL ; \2\ = BNO080_EVN_SCL

(kicad_pcb
	(version 20260206)
	(generator "pcbnew")
	(generator_version "10.0")
	(general
		(thickness 1.6)
		(legacy_teardrops no)
	)
	(paper "A4")
	(title_block
		(title "timecard-production-celestica-r4006 — R4006-B0001-02_R01.brd")
		(comment 1 "Time Appliance Project (Time Card) / footprints 797-798 of 1113")
	)
	(layers
		(0 "F.Cu" signal "TOP")
		(4 "In1.Cu" signal "L02_GND1")
		(6 "In2.Cu" signal "L03_SIG1")
		(8 "In3.Cu" signal "L04_GND2")
		(10 "In4.Cu" signal "L05_VCC1")
		(12 "In5.Cu" signal "L06_VCC2")
		(14 "In6.Cu" signal "L07_GND3")
		(16 "In7.Cu" signal "L08_SIG2")
		(18 "In8.Cu" signal "L09_GND4")
		(2 "B.Cu" signal "BOTTOM")
		(9 "F.Adhes" user "F.Adhesive")
		(11 "B.Adhes" user "B.Adhesive")
		(13 "F.Paste" user "Package Geometry/Pastemask Top")
		(15 "B.Paste" user "Package Geometry/Pastemask Bottom")
		(5 "F.SilkS" user "Ref Des/Silkscreen Top")
		(7 "B.SilkS" user "Ref Des/Silkscreen Bottom")
		(1 "F.Mask" user "Board Geometry/Soldermask Top")
		(3 "B.Mask" user "Board Geometry/Soldermask Bottom")
		(17 "Dwgs.User" user "User.Drawings")
		(19 "Cmts.User" user "User.Comments")
		(21 "Eco1.User" user "User.Eco1")
		(23 "Eco2.User" user "User.Eco2")
		(25 "Edge.Cuts" user "Board Geometry/Outline")
		(27 "Margin" user)
		(31 "F.CrtYd" user "Package Geometry/Place Bound Top")
		(29 "B.CrtYd" user "Package Geometry/Place Bound Bottom")
		(35 "F.Fab" user "Ref Des/Assembly Top")
		(33 "B.Fab" user "Ref Des/Assembly Bottom")
	)
	(footprint ""
		(layer "B.Cu")
		(at 80.899 -96.266 90)
		(property "Reference" "R39"
			(at -0.127 -1.69037 270)
			(unlocked yes)
			(layer "B.SilkS")
			(effects
				(font
					(size 0.7874 0.5842)
					(thickness 0.1524)
				)
				(justify mirror)
			)
		)
		(property "Value" "VAL*"
			(at -0.0508 3.159506 90)
			(unlocked yes)
			(layer "B.Fab")
			(hide yes)
			(effects
				(font
					(size 0.7874 0.5842)
					(thickness 0.1524)
				)
				(justify mirror)
			)
		)
		(property "Device Type" "RESISTOR-G157-12R20-01,2.2OHM,A"
			(at 0 2.194306 90)
			(unlocked yes)
			(layer "B.Fab")
			(hide yes)
			(effects
				(font
					(size 0.7874 0.5842)
					(thickness 0.1524)
				)
				(justify mirror)
			)
		)
		(property "User Part Number" "PARTNUM*"
			(at -0.0508 5.089906 90)
			(unlocked yes)
			(layer "Cmts.User")
			(hide yes)
			(effects
				(font
					(size 0.7874 0.5842)
					(thickness 0.1524)
				)
				(justify mirror)
			)
		)
		(property "Tolerance" "TOL*"
			(at -0.0508 4.124706 90)
			(unlocked yes)
			(layer "Cmts.User")
			(hide yes)
			(effects
				(font
					(size 0.7874 0.5842)
					(thickness 0.1524)
				)
				(justify mirror)
			)
		)
		(duplicate_pad_numbers_are_jumpers no)
		(fp_line
			(start 1.5748 -0.9398)
			(end 1.5748 0.9398)
			(stroke
				(width 0.1)
				(type default)
			)
			(layer "B.SilkS")
		)
		(fp_line
			(start -1.5748 -0.9398)
			(end 1.5748 -0.9398)
			(stroke
				(width 0.1)
				(type default)
			)
			(layer "B.SilkS")
		)
		(fp_line
			(start 1.5748 0.9398)
			(end -1.5748 0.9398)
			(stroke
				(width 0.1)
				(type default)
			)
			(layer "B.SilkS")
		)
		(fp_line
			(start -1.5748 0.9398)
			(end -1.5748 -0.9398)
			(stroke
				(width 0.1)
				(type default)
			)
			(layer "B.SilkS")
		)
		(fp_rect
			(start -1.5748 0.9398)
			(end 1.5748 -0.9398)
			(stroke
				(width 0)
				(type default)
			)
			(fill no)
			(layer "B.CrtYd")
		)
		(fp_line
			(start 1.016 -0.635)
			(end 1.016 0.635)
			(stroke
				(width 0.1)
				(type default)
			)
			(layer "B.Fab")
		)
		(fp_line
			(start -1.016 -0.635)
			(end 1.016 -0.635)
			(stroke
				(width 0.1)
				(type default)
			)
			(layer "B.Fab")
		)
		(fp_line
			(start 1.016 0.635)
			(end -1.016 0.635)
			(stroke
				(width 0.1)
				(type default)
			)
			(layer "B.Fab")
		)
		(fp_line
			(start -1.016 0.635)
			(end -1.016 -0.635)
			(stroke
				(width 0.1)
				(type default)
			)
			(layer "B.Fab")
		)
		(pad "1" smd rect
			(at 0.8382 0 270)
			(size 0.9652 1.3716)
			(layers "B.Cu" "B.Mask" "B.Paste")
			(net "UNNAMED_517_CAPACITOR_I29_2")
		)
		(pad "2" smd rect
			(at -0.8382 0 270)
			(size 0.9652 1.3716)
			(layers "B.Cu" "B.Mask" "B.Paste")
			(net "SG")
		)
		(zone
			(layer "B.Cu")
			(hatch none 0.5)
			(connect_pads
				(clearance 0)
			)
			(min_thickness 0.25)
			(keepout
				(tracks allowed)
				(vias not_allowed)
				(pads allowed)
				(copperpour not_allowed)
				(footprints allowed)
			)
			(placement
				(enabled no)
				(sheetname "")
			)
			(fill
				(thermal_gap 0.5)
				(thermal_bridge_width 0.5)
				(island_removal_mode 0)
			)
			(polygon
				(pts
					(xy 81.534 -96.0374) (xy 81.534 -96.4946) (xy 80.264 -96.4946) (xy 80.264 -96.0374)
				)
			)
		)
	)
	(footprint ""
		(layer "B.Cu")
		(at 85.09 -73.279 -90)
		(property "Reference" "R363"
			(at 3.556 0.03937 270)
			(unlocked yes)
			(layer "B.SilkS")
			(effects
				(font
					(size 0.7874 0.5842)
					(thickness 0.1524)
				)
				(justify mirror)
			)
		)
		(property "Value" "VAL*"
			(at -0.02032 2.13233 270)
			(unlocked yes)
			(layer "B.Fab")
			(hide yes)
			(effects
				(font
					(size 0.7874 0.5842)
					(thickness 0.1524)
				)
				(justify mirror)
			)
		)
		(property "Tolerance" "TOL*"
			(at -0.044704 3.05435 270)
			(unlocked yes)
			(layer "Cmts.User")
			(hide yes)
			(effects
				(font
					(size 0.7874 0.5842)
					(thickness 0.1524)
				)
				(justify mirror)
			)
		)
		(property "User Part Number" "PARTNUM*"
			(at -0.02032 4.024884 270)
			(unlocked yes)
			(layer "Cmts.User")
			(hide yes)
			(effects
				(font
					(size 0.7874 0.5842)
					(thickness 0.1524)
				)
				(justify mirror)
			)
		)
		(property "Device Type" "RESISTOR-G155-133R0-01,33OHM,1%"
			(at -0.008382 1.210564 270)
			(unlocked yes)
			(layer "B.Fab")
			(hide yes)
			(effects
				(font
					(size 0.7874 0.5842)
					(thickness 0.1524)
				)
				(justify mirror)
			)
		)
		(duplicate_pad_numbers_are_jumpers no)
		(fp_line
			(start -1.143 0.5588)
			(end -1.143 -0.5588)
			(stroke
				(width 0.1)
				(type default)
			)
			(layer "B.SilkS")
		)
		(fp_line
			(start 1.143 0.5588)
			(end -1.143 0.5588)
			(stroke
				(width 0.1)
				(type default)
			)
			(layer "B.SilkS")
		)
		(fp_line
			(start -1.143 -0.5588)
			(end 1.143 -0.5588)
			(stroke
				(width 0.1)
				(type default)
			)
			(layer "B.SilkS")
		)
		(fp_line
			(start 1.143 -0.5588)
			(end 1.143 0.5588)
			(stroke
				(width 0.1)
				(type default)
			)
			(layer "B.SilkS")
		)
		(fp_rect
			(start 1.143 0.5588)
			(end -1.143 -0.5588)
			(stroke
				(width 0)
				(type default)
			)
			(fill no)
			(layer "B.CrtYd")
		)
		(fp_line
			(start -0.508 0.3048)
			(end -0.508 -0.3048)
			(stroke
				(width 0.1)
				(type default)
			)
			(layer "B.Fab")
		)
		(fp_line
			(start 0.508 0.3048)
			(end -0.508 0.3048)
			(stroke
				(width 0.1)
				(type default)
			)
			(layer "B.Fab")
		)
		(fp_line
			(start -0.508 -0.3048)
			(end 0.508 -0.3048)
			(stroke
				(width 0.1)
				(type default)
			)
			(layer "B.Fab")
		)
		(fp_line
			(start 0.508 -0.3048)
			(end 0.508 0.3048)
			(stroke
				(width 0.1)
				(type default)
			)
			(layer "B.Fab")
		)
		(pad "1" smd rect
			(at 0.5334 0 90)
			(size 0.7112 0.6096)
			(layers "B.Cu" "B.Mask" "B.Paste")
			(net "R_BNO080_EVN_SCL")
		)
		(pad "2" smd rect
			(at -0.5334 0 90)
			(size 0.7112 0.6096)
			(layers "B.Cu" "B.Mask" "B.Paste")
			(net "BNO080_EVN_SCL")
		)
		(zone
			(layer "B.Cu")
			(hatch none 0.5)
			(connect_pads
				(clearance 0)
			)
			(min_thickness 0.25)
			(keepout
				(tracks allowed)
				(vias not_allowed)
				(pads allowed)
				(copperpour not_allowed)
				(footprints allowed)
			)
			(placement
				(enabled no)
				(sheetname "")
			)
			(fill
				(thermal_gap 0.5)
				(thermal_bridge_width 0.5)
				(island_removal_mode 0)
			)
			(polygon
				(pts
					(xy 84.7852 -73.2028) (xy 85.3948 -73.2028) (xy 85.3948 -73.3552) (xy 84.7852 -73.3552)
				)
			)
		)
		(zone
			(layer "B.Cu")
			(hatch none 0.5)
			(connect_pads
				(clearance 0)
			)
			(min_thickness 0.25)
			(keepout
				(tracks not_allowed)
				(vias allowed)
				(pads allowed)
				(copperpour not_allowed)
				(footprints allowed)
			)
			(placement
				(enabled no)
				(sheetname "")
			)
			(fill
				(thermal_gap 0.5)
				(thermal_bridge_width 0.5)
				(island_removal_mode 0)
			)
			(polygon
				(pts
					(xy 84.7852 -73.2028) (xy 85.3948 -73.2028) (xy 85.3948 -73.3552) (xy 84.7852 -73.3552)
				)
			)
		)
	)
)
